# BASEBOARD_FAB2 (Tioga Pass) — schematic netlist excerpt (pin names and nets, part order shuffled) for the footprints in the layout excerpt that follows; sources: Cadence DE-HDL packaged netlist, KiCad conversion of Wiwynn_Tioga_Pass_MB.brd

C2R4  CAP_A  0.1UF 16V 10% X7R  pkg 0402V  page 192 : A = P3V3_STBY ; B = GND

U2T2  TTL1G32_A  74LVC1G32 IC  pkg SOT  page 154
  A  = FM_BACKUP_BIOS_SEL_N
  B  = SPI_SWITCH_CS0_N
  Y  = SPI_CS0_SECONDARY_N

R9P32  RES  0.0 5% CHIP  pkg 0402  page 209 : A = VR_PVCCIN_CPU1_PH5_VCIN ; B = P5V_STBY

(kicad_pcb
	(version 20260206)
	(generator "pcbnew")
	(generator_version "10.0")
	(general
		(thickness 1.6)
		(legacy_teardrops no)
	)
	(paper "A4")
	(title_block
		(title "Wiwynn_Tioga_Pass_MB.brd")
		(comment 1 "Tioga Pass / footprints 2981-2983 of 4770")
	)
	(layers
		(0 "F.Cu" signal "TOP")
		(4 "In1.Cu" signal "L2GND")
		(6 "In2.Cu" signal "L3")
		(8 "In3.Cu" signal "L4GND")
		(10 "In4.Cu" signal "L5")
		(12 "In5.Cu" signal "L6GND")
		(14 "In6.Cu" signal "L7VCC")
		(16 "In7.Cu" signal "L8VCC")
		(18 "In8.Cu" signal "L9GND")
		(20 "In9.Cu" signal "L10")
		(22 "In10.Cu" signal "L11GND")
		(24 "In11.Cu" signal "L12")
		(26 "In12.Cu" signal "L13GND")
		(2 "B.Cu" signal "BOTTOM")
		(9 "F.Adhes" user "F.Adhesive")
		(11 "B.Adhes" user "B.Adhesive")
		(13 "F.Paste" user "Package Geometry/Pastemask Top")
		(15 "B.Paste" user "Package Geometry/Pastemask Bottom")
		(5 "F.SilkS" user "Ref Des/Silkscreen Top")
		(7 "B.SilkS" user "Ref Des/Silkscreen Bottom")
		(1 "F.Mask" user "Board Geometry/Soldermask Top")
		(3 "B.Mask" user "Board Geometry/Soldermask Bottom")
		(17 "Dwgs.User" user "User.Drawings")
		(19 "Cmts.User" user "User.Comments")
		(21 "Eco1.User" user "User.Eco1")
		(23 "Eco2.User" user "User.Eco2")
		(25 "Edge.Cuts" user "Board Geometry/Outline")
		(27 "Margin" user)
		(31 "F.CrtYd" user "Package Geometry/Place Bound Top")
		(29 "B.CrtYd" user "Package Geometry/Place Bound Bottom")
		(35 "F.Fab" user "Ref Des/Assembly Top")
		(33 "B.Fab" user "Ref Des/Assembly Bottom")
	)
	(footprint ""
		(layer "B.Cu")
		(at 32.2834 -87.0204 90)
		(property "Reference" "R9P32"
			(at 0 0 90)
			(layer "B.SilkS")
			(hide yes)
			(effects
				(font
					(size 1.27 1.27)
				)
				(justify mirror)
			)
		)
		(property "Value" ""
			(at 0 0 90)
			(layer "B.Fab")
			(effects
				(font
					(size 1.27 1.27)
				)
				(justify mirror)
			)
		)
		(duplicate_pad_numbers_are_jumpers no)
		(fp_poly
			(pts
				(xy 0.2794 -0.1016) (xy -0.2794 -0.1016) (xy -0.2794 0.9906) (xy 0.2794 0.9906)
			)
			(stroke
				(width 0)
				(type default)
			)
			(fill no)
			(layer "B.CrtYd")
		)
		(fp_line
			(start 0.2794 -0.1016)
			(end 0.2794 0.9906)
			(stroke
				(width 0.1)
				(type default)
			)
			(layer "B.Fab")
		)
		(fp_line
			(start -0.2794 -0.1016)
			(end 0.2794 -0.1016)
			(stroke
				(width 0.1)
				(type default)
			)
			(layer "B.Fab")
		)
		(fp_line
			(start 0.2794 0.9906)
			(end -0.2794 0.9906)
			(stroke
				(width 0.1)
				(type default)
			)
			(layer "B.Fab")
		)
		(fp_line
			(start -0.2794 0.9906)
			(end -0.2794 -0.1016)
			(stroke
				(width 0.1)
				(type default)
			)
			(layer "B.Fab")
		)
		(pad "1" smd rect
			(at 0 0 270)
			(size 0.508 0.508)
			(layers "B.Cu" "B.Mask" "B.Paste")
			(net "VR_PVCCIN_CPU1_PH5_VCIN")
		)
		(pad "2" smd rect
			(at 0 0.889 270)
			(size 0.508 0.508)
			(layers "B.Cu" "B.Mask" "B.Paste")
			(net "P5V_STBY")
		)
		(zone
			(layer "B.Cu")
			(hatch none 0.5)
			(connect_pads
				(clearance 0)
			)
			(min_thickness 0.25)
			(keepout
				(tracks allowed)
				(vias not_allowed)
				(pads allowed)
				(copperpour not_allowed)
				(footprints allowed)
			)
			(placement
				(enabled no)
				(sheetname "")
			)
			(fill
				(thermal_gap 0.5)
				(thermal_bridge_width 0.5)
				(island_removal_mode 0)
			)
			(polygon
				(pts
					(xy 32.5374 -87.2744) (xy 32.5374 -86.7664) (xy 32.9184 -86.7664) (xy 32.9184 -87.2744)
				)
			)
		)
		(zone
			(layer "B.Cu")
			(hatch none 0.5)
			(connect_pads
				(clearance 0)
			)
			(min_thickness 0.25)
			(keepout
				(tracks not_allowed)
				(vias allowed)
				(pads allowed)
				(copperpour not_allowed)
				(footprints allowed)
			)
			(placement
				(enabled no)
				(sheetname "")
			)
			(fill
				(thermal_gap 0.5)
				(thermal_bridge_width 0.5)
				(island_removal_mode 0)
			)
			(polygon
				(pts
					(xy 32.9184 -87.2744) (xy 32.9184 -86.7664) (xy 32.5374 -86.7664) (xy 32.5374 -87.2744)
				)
			)
		)
	)
	(footprint ""
		(layer "B.Cu")
		(at 391.3251 -64.381888 180)
		(property "Reference" "U2T2"
			(at 0.67564 -2.27203 180)
			(unlocked yes)
			(layer "B.SilkS")
			(effects
				(font
					(size 0.7874 0.5842)
					(thickness 0.1524)
				)
				(justify left mirror)
			)
		)
		(property "Value" ""
			(at 0 0 0)
			(layer "B.Fab")
			(effects
				(font
					(size 1.27 1.27)
				)
				(justify mirror)
			)
		)
		(duplicate_pad_numbers_are_jumpers no)
		(fp_circle
			(center 0.4699 -0.8382)
			(end 0.3429 -0.8382)
			(stroke
				(width 0.254)
				(type default)
			)
			(fill no)
			(layer "B.SilkS")
		)
		(fp_poly
			(pts
				(xy -0.21463 -0.450088) (xy -1.56337 -0.450088) (xy -1.56337 1.75006) (xy -0.21463 1.75006)
			)
			(stroke
				(width 0)
				(type default)
			)
			(fill no)
			(layer "B.CrtYd")
		)
		(fp_line
			(start -0.21463 1.75006)
			(end -0.21463 -0.450088)
			(stroke
				(width 0.1)
				(type default)
			)
			(layer "B.Fab")
		)
		(fp_line
			(start -0.21463 -0.450088)
			(end -1.56337 -0.450088)
			(stroke
				(width 0.1)
				(type default)
			)
			(layer "B.Fab")
		)
		(fp_line
			(start -1.56337 1.75006)
			(end -0.21463 1.75006)
			(stroke
				(width 0.1)
				(type default)
			)
			(layer "B.Fab")
		)
		(fp_line
			(start -1.56337 -0.450088)
			(end -1.56337 1.75006)
			(stroke
				(width 0.1)
				(type default)
			)
			(layer "B.Fab")
		)
		(fp_circle
			(center 0.4699 -0.8382)
			(end 0.3429 -0.8382)
			(stroke
				(width 0.254)
				(type default)
			)
			(fill no)
			(layer "B.Fab")
		)
		(pad "1" smd rect
			(at 0 0)
			(size 1.016 0.381)
			(layers "B.Cu" "B.Mask" "B.Paste")
			(net "FM_BACKUP_BIOS_SEL_N")
		)
		(pad "2" smd rect
			(at 0 0.649986)
			(size 1.016 0.381)
			(layers "B.Cu" "B.Mask" "B.Paste")
			(net "SPI_SWITCH_CS0_N")
		)
		(pad "3" smd rect
			(at 0 1.299972)
			(size 1.016 0.381)
			(layers "B.Cu" "B.Mask" "B.Paste")
			(net "GND")
		)
		(pad "4" smd rect
			(at -1.778 1.299972)
			(size 1.016 0.381)
			(layers "B.Cu" "B.Mask" "B.Paste")
			(net "SPI_CS0_SECONDARY_N")
		)
		(pad "5" smd rect
			(at -1.778 0)
			(size 1.016 0.381)
			(layers "B.Cu" "B.Mask" "B.Paste")
			(net "P3V3_STBY")
		)
	)
	(footprint ""
		(layer "B.Cu")
		(at 369.944904 -69.894196 180)
		(property "Reference" "C2R4"
			(at 0 0 0)
			(layer "B.SilkS")
			(hide yes)
			(effects
				(font
					(size 1.27 1.27)
				)
				(justify mirror)
			)
		)
		(property "Value" ""
			(at 0 0 0)
			(layer "B.Fab")
			(effects
				(font
					(size 1.27 1.27)
				)
				(justify mirror)
			)
		)
		(duplicate_pad_numbers_are_jumpers no)
		(fp_rect
			(start 0.2794 0.9144)
			(end -0.2794 -0.1143)
			(stroke
				(width 0)
				(type default)
			)
			(fill no)
			(layer "B.CrtYd")
		)
		(fp_line
			(start 0.2794 0.9144)
			(end 0.2794 -0.1143)
			(stroke
				(width 0.1)
				(type default)
			)
			(layer "B.Fab")
		)
		(fp_line
			(start 0.2794 -0.1143)
			(end -0.2794 -0.1143)
			(stroke
				(width 0.1)
				(type default)
			)
			(layer "B.Fab")
		)
		(fp_line
			(start -0.2794 0.9144)
			(end 0.2794 0.9144)
			(stroke
				(width 0.1)
				(type default)
			)
			(layer "B.Fab")
		)
		(fp_line
			(start -0.2794 -0.1143)
			(end -0.2794 0.9144)
			(stroke
				(width 0.1)
				(type default)
			)
			(layer "B.Fab")
		)
		(pad "1" smd custom
			(at 0 0 90)
			(size 0.10414 0.10414)
			(layers "B.Cu" "B.Mask" "B.Paste")
			(net "P3V3_STBY")
			(options
				(clearance outline)
				(anchor circle)
			)
			(primitives
				(gr_poly
					(pts
						(xy -0.20828 -0.08636) (xy -0.20828 0.08636) (xy -0.08636 0.20828) (xy 0.086614 0.20828) (xy 0.20828 0.086614)
						(xy 0.20828 -0.08636) (xy 0.08636 -0.20828) (xy -0.08636 -0.20828)
					)
					(width 0)
					(fill yes)
				)
			)
		)
		(pad "2" smd custom
			(at 0 0.8001 90)
			(size 0.10414 0.10414)
			(layers "B.Cu" "B.Mask" "B.Paste")
			(net "GND")
			(options
				(clearance outline)
				(anchor circle)
			)
			(primitives
				(gr_poly
					(pts
						(xy -0.20828 -0.08636) (xy -0.20828 0.08636) (xy -0.08636 0.20828) (xy 0.086614 0.20828) (xy 0.20828 0.086614)
						(xy 0.20828 -0.08636) (xy 0.08636 -0.20828) (xy -0.08636 -0.20828)
					)
					(width 0)
					(fill yes)
				)
			)
		)
		(zone
			(layer "B.Cu")
			(hatch none 0.5)
			(connect_pads
				(clearance 0)
			)
			(min_thickness 0.25)
			(keepout
				(tracks not_allowed)
				(vias allowed)
				(pads allowed)
				(copperpour not_allowed)
				(footprints allowed)
			)
			(placement
				(enabled no)
				(sheetname "")
			)
			(fill
				(thermal_gap 0.5)
				(thermal_bridge_width 0.5)
				(island_removal_mode 0)
			)
			(polygon
				(pts
					(xy 369.857274 -70.103746) (xy 369.857274 -70.484746) (xy 370.032534 -70.484746) (xy 370.032788 -70.103746)
				)
			)
		)
		(zone
			(layer "B.Cu")
			(hatch none 0.5)
			(connect_pads
				(clearance 0)
			)
			(min_thickness 0.25)
			(keepout
				(tracks allowed)
				(vias not_allowed)
				(pads allowed)
				(copperpour not_allowed)
				(footprints allowed)
			)
			(placement
				(enabled no)
				(sheetname "")
			)
			(fill
				(thermal_gap 0.5)
				(thermal_bridge_width 0.5)
				(island_removal_mode 0)
			)
			(polygon
				(pts
					(xy 369.857274 -70.103746) (xy 369.857274 -70.484746) (xy 370.032534 -70.484746) (xy 370.032788 -70.103746)
				)
			)
		)
	)
)
